# S9S_MB_2U (Grand Teton) — schematic netlist excerpt (pin names and nets, part order shuffled) for the footprints in the layout excerpt that follows; sources: Cadence DE-HDL packaged netlist, KiCad conversion of 03242023_DA0F0TMBIJ0_F0T_Motherboard_J_brd_V01_OCP.brd

R2982  Q_RES  0 5% CHIP  pkg 0402LF  page 227 : A = SMB_IOEXP_3V3AUX_SCL ; B = SMB_IOEXP_3V3AUX_SCL_R1
R202  Q_RES  100 1% CHIP  pkg 0402LF  page 123 : A = PVNN_TERM_CPU1 ; B = H_CPU1_MEMTRIP_LVC1_R_N

(kicad_pcb
	(version 20260206)
	(generator "pcbnew")
	(generator_version "10.0")
	(general
		(thickness 1.6)
		(legacy_teardrops no)
	)
	(paper "A4")
	(title_block
		(title "03242023_DA0F0TMBIJ0_F0T_Motherboard_J_brd_V01_OCP.brd")
		(comment 1 "Grand Teton / footprints 100-101 of 6105")
	)
	(layers
		(0 "F.Cu" signal "TOP")
		(4 "In1.Cu" signal "GND")
		(6 "In2.Cu" signal "IN1")
		(8 "In3.Cu" signal "GND1")
		(10 "In4.Cu" signal "IN2")
		(12 "In5.Cu" signal "GND2")
		(14 "In6.Cu" signal "IN3")
		(16 "In7.Cu" signal "GND3")
		(18 "In8.Cu" signal "VCC")
		(20 "In9.Cu" signal "VCC1")
		(22 "In10.Cu" signal "GND4")
		(24 "In11.Cu" signal "IN4")
		(26 "In12.Cu" signal "GND5")
		(28 "In13.Cu" signal "IN5")
		(30 "In14.Cu" signal "GND6")
		(32 "In15.Cu" signal "IN6")
		(34 "In16.Cu" signal "GND7")
		(2 "B.Cu" signal "BOTTOM")
		(9 "F.Adhes" user "F.Adhesive")
		(11 "B.Adhes" user "B.Adhesive")
		(13 "F.Paste" user "Package Geometry/Pastemask Top")
		(15 "B.Paste" user "Package Geometry/Pastemask Bottom")
		(5 "F.SilkS" user "Ref Des/Silkscreen Top")
		(7 "B.SilkS" user "Ref Des/Silkscreen Bottom")
		(1 "F.Mask" user "Board Geometry/Soldermask Top")
		(3 "B.Mask" user "Board Geometry/Soldermask Bottom")
		(17 "Dwgs.User" user "User.Drawings")
		(19 "Cmts.User" user "User.Comments")
		(21 "Eco1.User" user "User.Eco1")
		(23 "Eco2.User" user "User.Eco2")
		(25 "Edge.Cuts" user "Board Geometry/Outline")
		(27 "Margin" user)
		(31 "F.CrtYd" user "Package Geometry/Place Bound Top")
		(29 "B.CrtYd" user "Package Geometry/Place Bound Bottom")
		(35 "F.Fab" user "Ref Des/Assembly Top")
		(33 "B.Fab" user "Ref Des/Assembly Bottom")
	)
	(footprint ""
		(layer "F.Cu")
		(at 132.51688 -100.167948 -90)
		(property "Reference" "R202"
			(at 0 0 270)
			(layer "F.SilkS")
			(hide yes)
			(effects
				(font
					(size 1.27 1.27)
				)
			)
		)
		(property "Value" ""
			(at 0 0 270)
			(layer "F.Fab")
			(effects
				(font
					(size 1.27 1.27)
				)
			)
		)
		(duplicate_pad_numbers_are_jumpers no)
		(fp_line
			(start -0.7874 0.4064)
			(end -0.7874 -0.4064)
			(stroke
				(width 0.1524)
				(type default)
			)
			(layer "F.SilkS")
		)
		(fp_line
			(start 0.7874 0.4064)
			(end -0.7874 0.4064)
			(stroke
				(width 0.1524)
				(type default)
			)
			(layer "F.SilkS")
		)
		(fp_line
			(start -0.7874 -0.4064)
			(end 0.7874 -0.4064)
			(stroke
				(width 0.1524)
				(type default)
			)
			(layer "F.SilkS")
		)
		(fp_line
			(start 0.7874 -0.4064)
			(end 0.7874 0.4064)
			(stroke
				(width 0.1524)
				(type default)
			)
			(layer "F.SilkS")
		)
		(fp_line
			(start -0.67945 0.3048)
			(end -0.67945 -0.305054)
			(stroke
				(width 0.1)
				(type default)
			)
			(layer "F.Fab")
		)
		(fp_line
			(start -0.12065 0.3048)
			(end -0.67945 0.3048)
			(stroke
				(width 0.1)
				(type default)
			)
			(layer "F.Fab")
		)
		(fp_line
			(start 0.120396 0.3048)
			(end 0.120396 0.2794)
			(stroke
				(width 0.1)
				(type default)
			)
			(layer "F.Fab")
		)
		(fp_line
			(start 0.67945 0.3048)
			(end 0.120396 0.3048)
			(stroke
				(width 0.1)
				(type default)
			)
			(layer "F.Fab")
		)
		(fp_line
			(start -0.12065 0.2794)
			(end -0.12065 0.3048)
			(stroke
				(width 0.1)
				(type default)
			)
			(layer "F.Fab")
		)
		(fp_line
			(start 0.120396 0.2794)
			(end -0.12065 0.2794)
			(stroke
				(width 0.1)
				(type default)
			)
			(layer "F.Fab")
		)
		(fp_line
			(start -0.12065 -0.2794)
			(end 0.12065 -0.2794)
			(stroke
				(width 0.1)
				(type default)
			)
			(layer "F.Fab")
		)
		(fp_line
			(start 0.12065 -0.2794)
			(end 0.12065 -0.3048)
			(stroke
				(width 0.1)
				(type default)
			)
			(layer "F.Fab")
		)
		(fp_line
			(start 0.12065 -0.3048)
			(end 0.67945 -0.3048)
			(stroke
				(width 0.1)
				(type default)
			)
			(layer "F.Fab")
		)
		(fp_line
			(start 0.67945 -0.3048)
			(end 0.67945 0.3048)
			(stroke
				(width 0.1)
				(type default)
			)
			(layer "F.Fab")
		)
		(fp_line
			(start -0.67945 -0.305054)
			(end -0.12065 -0.305054)
			(stroke
				(width 0.1)
				(type default)
			)
			(layer "F.Fab")
		)
		(fp_line
			(start -0.12065 -0.305054)
			(end -0.12065 -0.2794)
			(stroke
				(width 0.1)
				(type default)
			)
			(layer "F.Fab")
		)
		(pad "1" smd circle
			(at -0.40005 0 270)
			(size 0 0)
			(layers "F.Cu" "F.Mask" "F.Paste")
			(net "PVNN_TERM_CPU1")
		)
		(pad "2" smd circle
			(at 0.40005 0 270)
			(size 0 0)
			(layers "F.Cu" "F.Mask" "F.Paste")
			(net "H_CPU1_MEMTRIP_LVC1_R_N")
		)
	)
	(footprint ""
		(layer "F.Cu")
		(at 13.546582 -423.629836 -90)
		(property "Reference" "R2982"
			(at 0 0 270)
			(layer "F.SilkS")
			(hide yes)
			(effects
				(font
					(size 1.27 1.27)
				)
			)
		)
		(property "Value" ""
			(at 0 0 270)
			(layer "F.Fab")
			(effects
				(font
					(size 1.27 1.27)
				)
			)
		)
		(duplicate_pad_numbers_are_jumpers no)
		(fp_line
			(start -0.7874 0.4064)
			(end -0.7874 -0.4064)
			(stroke
				(width 0.1524)
				(type default)
			)
			(layer "F.SilkS")
		)
		(fp_line
			(start 0.7874 0.4064)
			(end -0.7874 0.4064)
			(stroke
				(width 0.1524)
				(type default)
			)
			(layer "F.SilkS")
		)
		(fp_line
			(start -0.7874 -0.4064)
			(end 0.7874 -0.4064)
			(stroke
				(width 0.1524)
				(type default)
			)
			(layer "F.SilkS")
		)
		(fp_line
			(start 0.7874 -0.4064)
			(end 0.7874 0.4064)
			(stroke
				(width 0.1524)
				(type default)
			)
			(layer "F.SilkS")
		)
		(fp_line
			(start -0.67945 0.3048)
			(end -0.67945 -0.305054)
			(stroke
				(width 0.1)
				(type default)
			)
			(layer "F.Fab")
		)
		(fp_line
			(start -0.12065 0.3048)
			(end -0.67945 0.3048)
			(stroke
				(width 0.1)
				(type default)
			)
			(layer "F.Fab")
		)
		(fp_line
			(start 0.120396 0.3048)
			(end 0.120396 0.2794)
			(stroke
				(width 0.1)
				(type default)
			)
			(layer "F.Fab")
		)
		(fp_line
			(start 0.67945 0.3048)
			(end 0.120396 0.3048)
			(stroke
				(width 0.1)
				(type default)
			)
			(layer "F.Fab")
		)
		(fp_line
			(start -0.12065 0.2794)
			(end -0.12065 0.3048)
			(stroke
				(width 0.1)
				(type default)
			)
			(layer "F.Fab")
		)
		(fp_line
			(start 0.120396 0.2794)
			(end -0.12065 0.2794)
			(stroke
				(width 0.1)
				(type default)
			)
			(layer "F.Fab")
		)
		(fp_line
			(start -0.12065 -0.2794)
			(end 0.12065 -0.2794)
			(stroke
				(width 0.1)
				(type default)
			)
			(layer "F.Fab")
		)
		(fp_line
			(start 0.12065 -0.2794)
			(end 0.12065 -0.3048)
			(stroke
				(width 0.1)
				(type default)
			)
			(layer "F.Fab")
		)
		(fp_line
			(start 0.12065 -0.3048)
			(end 0.67945 -0.3048)
			(stroke
				(width 0.1)
				(type default)
			)
			(layer "F.Fab")
		)
		(fp_line
			(start 0.67945 -0.3048)
			(end 0.67945 0.3048)
			(stroke
				(width 0.1)
				(type default)
			)
			(layer "F.Fab")
		)
		(fp_line
			(start -0.67945 -0.305054)
			(end -0.12065 -0.305054)
			(stroke
				(width 0.1)
				(type default)
			)
			(layer "F.Fab")
		)
		(fp_line
			(start -0.12065 -0.305054)
			(end -0.12065 -0.2794)
			(stroke
				(width 0.1)
				(type default)
			)
			(layer "F.Fab")
		)
		(pad "1" smd circle
			(at -0.40005 0 270)
			(size 0 0)
			(layers "F.Cu" "F.Mask" "F.Paste")
			(net "SMB_IOEXP_3V3AUX_SCL")
		)
		(pad "2" smd circle
			(at 0.40005 0 270)
			(size 0 0)
			(layers "F.Cu" "F.Mask" "F.Paste")
			(net "SMB_IOEXP_3V3AUX_SCL_R1")
		)
	)
)
